(kicad_pcb
	(version 20241229)
	(generator "pcbnew")
	(generator_version "9.0")
	(general
		(thickness 1.62)
		(legacy_teardrops no)
	)
	(paper "A3")
	(title_block
		(title "COM Express 7 Baseboard")
		(date "2025-02-04")
		(rev "1.1.2")
		(company "Antmicro Ltd")
		(comment 1 "www.antmicro.com")
		(comment 9 "footprints 730-735 of 802")
	)
	(layers
		(0 "F.Cu" signal)
		(4 "In1.Cu" signal)
		(6 "In2.Cu" signal)
		(8 "In3.Cu" signal)
		(10 "In4.Cu" signal)
		(12 "In5.Cu" signal)
		(14 "In6.Cu" signal)
		(2 "B.Cu" signal)
		(9 "F.Adhes" user "F.Adhesive")
		(11 "B.Adhes" user "B.Adhesive")
		(13 "F.Paste" user)
		(15 "B.Paste" user)
		(5 "F.SilkS" user "F.Silkscreen")
		(7 "B.SilkS" user "B.Silkscreen")
		(1 "F.Mask" user)
		(3 "B.Mask" user)
		(17 "Dwgs.User" user "User.Drawings")
		(19 "Cmts.User" user "User.Comments")
		(21 "Eco1.User" user "User.Eco1")
		(23 "Eco2.User" user "User.Eco2")
		(25 "Edge.Cuts" user)
		(27 "Margin" user)
		(31 "F.CrtYd" user "F.Courtyard")
		(29 "B.CrtYd" user "B.Courtyard")
		(35 "F.Fab" user)
		(33 "B.Fab" user)
	)
	(footprint "antmicro-footprints:R_0402_1005Metric"
		(layer "B.Cu")
		(at 309.824999 101.76 90)
		(descr "Resistor SMD 0402")
		(tags "resistor SMD 0402")
		(property "Reference" "R86"
			(at 3.06 0.455001 270)
			(layer "B.SilkS")
			(effects
				(font
					(size 0.7 0.7)
					(thickness 0.15)
				)
				(justify left bottom mirror)
			)
		)
		(property "Value" "R_10k_0402"
			(at -1.011843 -1.772047 90)
			(layer "B.Fab")
			(effects
				(font
					(size 0.7 0.7)
					(thickness 0.15)
				)
				(justify right bottom mirror)
			)
		)
		(property "Datasheet" "https://www.bourns.com/docs/product-datasheets/cr.pdf"
			(at 0 0 90)
			(layer "F.Fab")
			(hide yes)
			(effects
				(font
					(size 1.27 1.27)
					(thickness 0.15)
				)
			)
		)
		(property "Author" "Antmicro"
			(at 411.584999 -208.064999 0)
			(layer "B.Fab")
			(hide yes)
			(effects
				(font
					(size 1 1)
					(thickness 0.15)
				)
				(justify mirror)
			)
		)
		(property "License" "Apache-2.0"
			(at 411.584999 -208.064999 0)
			(layer "B.Fab")
			(hide yes)
			(effects
				(font
					(size 1 1)
					(thickness 0.15)
				)
				(justify mirror)
			)
		)
		(property "MPN" "CR0402-FX-1002GLF"
			(at 411.584999 -208.064999 0)
			(layer "B.Fab")
			(hide yes)
			(effects
				(font
					(size 1 1)
					(thickness 0.15)
				)
				(justify mirror)
			)
		)
		(property "Manufacturer" "Bourns"
			(at 411.584999 -208.064999 0)
			(layer "B.Fab")
			(hide yes)
			(effects
				(font
					(size 1 1)
					(thickness 0.15)
				)
				(justify mirror)
			)
		)
		(property "Public" "False"
			(at 411.584999 -208.064999 0)
			(layer "B.Fab")
			(hide yes)
			(effects
				(font
					(size 1 1)
					(thickness 0.15)
				)
				(justify mirror)
			)
		)
		(property "Tolerance" "1%"
			(at 411.584999 -208.064999 0)
			(layer "B.Fab")
			(hide yes)
			(effects
				(font
					(size 1 1)
					(thickness 0.15)
				)
				(justify mirror)
			)
		)
		(property "Val" "10k"
			(at 411.584999 -208.064999 0)
			(layer "B.Fab")
			(hide yes)
			(effects
				(font
					(size 1 1)
					(thickness 0.15)
				)
				(justify mirror)
			)
		)
		(sheetname "Power")
		(sheetfile "power.kicad_sch")
		(attr smd)
		(fp_rect
			(start -0.925 0.47)
			(end 0.925 -0.47)
			(stroke
				(width 0.05)
				(type default)
			)
			(fill no)
			(layer "B.CrtYd")
		)
		(fp_rect
			(start -0.5 0.25)
			(end 0.5 -0.25)
			(stroke
				(width 0.15)
				(type solid)
			)
			(fill no)
			(layer "B.Fab")
		)
		(pad "1" smd roundrect
			(at -0.48 0 90)
			(size 0.59 0.64)
			(layers "B.Cu" "B.Mask" "B.Paste")
			(roundrect_rratio 0.25)
			(net 574 "Net-(U19-EN)")
			(pintype "passive")
			(teardrops
				(best_length_ratio 0.2)
				(max_length 1)
				(best_width_ratio 0.9)
				(max_width 2)
				(curved_edges yes)
				(filter_ratio 0.9)
				(enabled yes)
				(allow_two_segments yes)
				(prefer_zone_connections yes)
			)
		)
		(pad "2" smd roundrect
			(at 0.48 0 90)
			(size 0.59 0.64)
			(layers "B.Cu" "B.Mask" "B.Paste")
			(roundrect_rratio 0.25)
			(net 52 "+5V")
			(pintype "passive")
			(teardrops
				(best_length_ratio 0.2)
				(max_length 1)
				(best_width_ratio 0.9)
				(max_width 2)
				(curved_edges yes)
				(filter_ratio 0.9)
				(enabled yes)
				(allow_two_segments yes)
				(prefer_zone_connections yes)
			)
		)
	)
	(footprint "antmicro-footprints:R_0402_1005Metric"
		(layer "B.Cu")
		(at 123.4 109.81 180)
		(descr "Resistor SMD 0402")
		(tags "resistor SMD 0402")
		(property "Reference" "R3"
			(at -2.35 -0.4 0)
			(layer "B.SilkS")
			(effects
				(font
					(size 0.7 0.7)
					(thickness 0.15)
				)
				(justify left bottom mirror)
			)
		)
		(property "Value" "R_0R_0402"
			(at -1.011843 -1.772047 0)
			(layer "B.Fab")
			(effects
				(font
					(size 0.7 0.7)
					(thickness 0.15)
				)
				(justify left bottom mirror)
			)
		)
		(property "Datasheet" "https://industrial.panasonic.com/cdbs/www-data/pdf/RDA0000/AOA0000C301.pdf"
			(at 0 0 180)
			(layer "F.Fab")
			(hide yes)
			(effects
				(font
					(size 1.27 1.27)
					(thickness 0.15)
				)
			)
		)
		(property "Author" "Antmicro"
			(at 246.8 219.62 0)
			(layer "B.Fab")
			(hide yes)
			(effects
				(font
					(size 1 1)
					(thickness 0.15)
				)
				(justify mirror)
			)
		)
		(property "Current" "1A"
			(at 246.8 219.62 0)
			(layer "B.Fab")
			(hide yes)
			(effects
				(font
					(size 1 1)
					(thickness 0.15)
				)
				(justify mirror)
			)
		)
		(property "License" "Apache-2.0"
			(at 246.8 219.62 0)
			(layer "B.Fab")
			(hide yes)
			(effects
				(font
					(size 1 1)
					(thickness 0.15)
				)
				(justify mirror)
			)
		)
		(property "MPN" "ERJ2GE0R00X"
			(at 246.8 219.62 0)
			(layer "B.Fab")
			(hide yes)
			(effects
				(font
					(size 1 1)
					(thickness 0.15)
				)
				(justify mirror)
			)
		)
		(property "Manufacturer" "Panasonic"
			(at 246.8 219.62 0)
			(layer "B.Fab")
			(hide yes)
			(effects
				(font
					(size 1 1)
					(thickness 0.15)
				)
				(justify mirror)
			)
		)
		(property "Public" "False"
			(at 246.8 219.62 0)
			(layer "B.Fab")
			(hide yes)
			(effects
				(font
					(size 1 1)
					(thickness 0.15)
				)
				(justify mirror)
			)
		)
		(property "Tolerance" ""
			(at 246.8 219.62 0)
			(layer "B.Fab")
			(hide yes)
			(effects
				(font
					(size 1 1)
					(thickness 0.15)
				)
				(justify mirror)
			)
		)
		(property "Val" "0R"
			(at 246.8 219.62 0)
			(layer "B.Fab")
			(hide yes)
			(effects
				(font
					(size 1 1)
					(thickness 0.15)
				)
				(justify mirror)
			)
		)
		(sheetname "2xUSB3.0+RJ45")
		(sheetfile "usb3+rj45.kicad_sch")
		(attr smd dnp)
		(fp_rect
			(start -0.925 0.47)
			(end 0.925 -0.47)
			(stroke
				(width 0.05)
				(type default)
			)
			(fill no)
			(layer "B.CrtYd")
		)
		(fp_rect
			(start -0.5 0.25)
			(end 0.5 -0.25)
			(stroke
				(width 0.15)
				(type solid)
			)
			(fill no)
			(layer "B.Fab")
		)
		(pad "1" smd roundrect
			(at -0.48 0 180)
			(size 0.59 0.64)
			(layers "B.Cu" "B.Mask" "B.Paste")
			(roundrect_rratio 0.25)
			(net 288 "/2xUSB3.0+RJ45/~{GBE0_LINK_1000}")
			(pintype "passive")
			(teardrops
				(best_length_ratio 0.2)
				(max_length 1)
				(best_width_ratio 0.9)
				(max_width 2)
				(curved_edges yes)
				(filter_ratio 0.9)
				(enabled yes)
				(allow_two_segments yes)
				(prefer_zone_connections yes)
			)
		)
		(pad "2" smd roundrect
			(at 0.48 0 180)
			(size 0.59 0.64)
			(layers "B.Cu" "B.Mask" "B.Paste")
			(roundrect_rratio 0.25)
			(net 156 "Net-(J1A-LED_D3)")
			(pintype "passive")
			(teardrops
				(best_length_ratio 0.2)
				(max_length 1)
				(best_width_ratio 0.9)
				(max_width 2)
				(curved_edges yes)
				(filter_ratio 0.9)
				(enabled yes)
				(allow_two_segments yes)
				(prefer_zone_connections yes)
			)
		)
	)
	(footprint "antmicro-footprints:C_0402_1005Metric"
		(layer "B.Cu")
		(at 130.79 132.87 180)
		(descr "Capacitor SMD 0402")
		(tags "capacitor SMD 0402")
		(property "Reference" "C197"
			(at 0.49 4.96 0)
			(layer "B.SilkS")
			(effects
				(font
					(size 0.7 0.7)
					(thickness 0.15)
				)
				(justify left bottom mirror)
			)
		)
		(property "Value" "C_100n_0402"
			(at -1.022927 -2.155213 0)
			(layer "B.Fab")
			(effects
				(font
					(size 0.7 0.7)
					(thickness 0.15)
				)
				(justify left bottom mirror)
			)
		)
		(property "Datasheet" "https://www.murata.com/products/productdetail?partno=GRM155R61H104KE14%23"
			(at 0 0 180)
			(layer "F.Fab")
			(hide yes)
			(effects
				(font
					(size 1.27 1.27)
					(thickness 0.15)
				)
			)
		)
		(property "Author" "Antmicro"
			(at 261.58 265.74 0)
			(layer "B.Fab")
			(hide yes)
			(effects
				(font
					(size 1 1)
					(thickness 0.15)
				)
				(justify mirror)
			)
		)
		(property "Dielectric" "X5R"
			(at 261.58 265.74 0)
			(layer "B.Fab")
			(hide yes)
			(effects
				(font
					(size 1 1)
					(thickness 0.15)
				)
				(justify mirror)
			)
		)
		(property "License" "Apache-2.0"
			(at 261.58 265.74 0)
			(layer "B.Fab")
			(hide yes)
			(effects
				(font
					(size 1 1)
					(thickness 0.15)
				)
				(justify mirror)
			)
		)
		(property "MPN" "GRM155R61H104KE14D"
			(at 261.58 265.74 0)
			(layer "B.Fab")
			(hide yes)
			(effects
				(font
					(size 1 1)
					(thickness 0.15)
				)
				(justify mirror)
			)
		)
		(property "Manufacturer" "Murata"
			(at 261.58 265.74 0)
			(layer "B.Fab")
			(hide yes)
			(effects
				(font
					(size 1 1)
					(thickness 0.15)
				)
				(justify mirror)
			)
		)
		(property "Public" "False"
			(at 261.58 265.74 0)
			(layer "B.Fab")
			(hide yes)
			(effects
				(font
					(size 1 1)
					(thickness 0.15)
				)
				(justify mirror)
			)
		)
		(property "Val" "100n"
			(at 261.58 265.74 0)
			(layer "B.Fab")
			(hide yes)
			(effects
				(font
					(size 1 1)
					(thickness 0.15)
				)
				(justify mirror)
			)
		)
		(property "Voltage" "50V"
			(at 261.58 265.74 0)
			(layer "B.Fab")
			(hide yes)
			(effects
				(font
					(size 1 1)
					(thickness 0.15)
				)
				(justify mirror)
			)
		)
		(sheetname "KR to SFI #2")
		(sheetfile "kr_sfi.kicad_sch")
		(attr smd)
		(fp_rect
			(start -0.925 0.47)
			(end 0.925 -0.47)
			(stroke
				(width 0.05)
				(type default)
			)
			(fill no)
			(layer "B.CrtYd")
		)
		(fp_line
			(start 0.504 0.25)
			(end -0.494 0.25)
			(stroke
				(width 0.15)
				(type solid)
			)
			(layer "B.Fab")
		)
		(fp_line
			(start 0.504 -0.248)
			(end 0.504 0.25)
			(stroke
				(width 0.15)
				(type solid)
			)
			(layer "B.Fab")
		)
		(fp_line
			(start -0.494 0.25)
			(end -0.494 -0.248)
			(stroke
				(width 0.15)
				(type solid)
			)
			(layer "B.Fab")
		)
		(fp_line
			(start -0.494 -0.248)
			(end 0.504 -0.248)
			(stroke
				(width 0.15)
				(type solid)
			)
			(layer "B.Fab")
		)
		(pad "1" smd roundrect
			(at -0.48 0 180)
			(size 0.59 0.64)
			(layers "B.Cu" "B.Mask" "B.Paste")
			(roundrect_rratio 0.25)
			(net 1 "GND")
			(pintype "passive")
			(teardrops
				(best_length_ratio 0.2)
				(max_length 1)
				(best_width_ratio 0.9)
				(max_width 2)
				(curved_edges yes)
				(filter_ratio 0.9)
				(enabled yes)
				(allow_two_segments yes)
				(prefer_zone_connections yes)
			)
		)
		(pad "2" smd roundrect
			(at 0.48 0 180)
			(size 0.59 0.64)
			(layers "B.Cu" "B.Mask" "B.Paste")
			(roundrect_rratio 0.25)
			(net 74 "+1V0")
			(pintype "passive")
			(teardrops
				(best_length_ratio 0.2)
				(max_length 1)
				(best_width_ratio 0.9)
				(max_width 2)
				(curved_edges yes)
				(filter_ratio 0.9)
				(enabled yes)
				(allow_two_segments yes)
				(prefer_zone_connections yes)
			)
		)
	)
	(footprint "antmicro-footprints:C_0402_1005Metric"
		(layer "B.Cu")
		(at 109.811 159.869 180)
		(descr "Capacitor SMD 0402")
		(tags "capacitor SMD 0402")
		(property "Reference" "C144"
			(at -3.739 -0.481 0)
			(layer "B.SilkS")
			(effects
				(font
					(size 0.7 0.7)
					(thickness 0.15)
				)
				(justify left bottom mirror)
			)
		)
		(property "Value" "C_220n_0402"
			(at -1.022927 -2.155213 0)
			(layer "B.Fab")
			(effects
				(font
					(size 0.7 0.7)
					(thickness 0.15)
				)
				(justify left bottom mirror)
			)
		)
		(property "Datasheet" "https://www.yageo.com/en/Chart/Download/pdf/CC0402KRX5R6BB224"
			(at 0 0 180)
			(layer "F.Fab")
			(hide yes)
			(effects
				(font
					(size 1.27 1.27)
					(thickness 0.15)
				)
			)
		)
		(property "Author" "Antmicro"
			(at 219.622 319.738 0)
			(layer "B.Fab")
			(hide yes)
			(effects
				(font
					(size 1 1)
					(thickness 0.15)
				)
				(justify mirror)
			)
		)
		(property "Dielectric" ""
			(at 219.622 319.738 0)
			(layer "B.Fab")
			(hide yes)
			(effects
				(font
					(size 1 1)
					(thickness 0.15)
				)
				(justify mirror)
			)
		)
		(property "License" "Apache-2.0"
			(at 219.622 319.738 0)
			(layer "B.Fab")
			(hide yes)
			(effects
				(font
					(size 1 1)
					(thickness 0.15)
				)
				(justify mirror)
			)
		)
		(property "MPN" "CC0402KRX5R6BB224"
			(at 219.622 319.738 0)
			(layer "B.Fab")
			(hide yes)
			(effects
				(font
					(size 1 1)
					(thickness 0.15)
				)
				(justify mirror)
			)
		)
		(property "Manufacturer" "YAGEO"
			(at 219.622 319.738 0)
			(layer "B.Fab")
			(hide yes)
			(effects
				(font
					(size 1 1)
					(thickness 0.15)
				)
				(justify mirror)
			)
		)
		(property "Public" "False"
			(at 219.622 319.738 0)
			(layer "B.Fab")
			(hide yes)
			(effects
				(font
					(size 1 1)
					(thickness 0.15)
				)
				(justify mirror)
			)
		)
		(property "Val" "220n"
			(at 219.622 319.738 0)
			(layer "B.Fab")
			(hide yes)
			(effects
				(font
					(size 1 1)
					(thickness 0.15)
				)
				(justify mirror)
			)
		)
		(property "Voltage" ""
			(at 219.622 319.738 0)
			(layer "B.Fab")
			(hide yes)
			(effects
				(font
					(size 1 1)
					(thickness 0.15)
				)
				(justify mirror)
			)
		)
		(sheetname "PCIe redriver")
		(sheetfile "pcie_redriver.kicad_sch")
		(attr smd)
		(fp_rect
			(start -0.925 0.47)
			(end 0.925 -0.47)
			(stroke
				(width 0.05)
				(type default)
			)
			(fill no)
			(layer "B.CrtYd")
		)
		(fp_line
			(start 0.504 0.25)
			(end -0.494 0.25)
			(stroke
				(width 0.15)
				(type solid)
			)
			(layer "B.Fab")
		)
		(fp_line
			(start 0.504 -0.248)
			(end 0.504 0.25)
			(stroke
				(width 0.15)
				(type solid)
			)
			(layer "B.Fab")
		)
		(fp_line
			(start -0.494 0.25)
			(end -0.494 -0.248)
			(stroke
				(width 0.15)
				(type solid)
			)
			(layer "B.Fab")
		)
		(fp_line
			(start -0.494 -0.248)
			(end 0.504 -0.248)
			(stroke
				(width 0.15)
				(type solid)
			)
			(layer "B.Fab")
		)
		(pad "1" smd roundrect
			(at -0.48 0 180)
			(size 0.59 0.64)
			(layers "B.Cu" "B.Mask" "B.Paste")
			(roundrect_rratio 0.25)
			(net 964 "/PCIe redriver/PCIe_{O}_C.TX2-")
			(pintype "passive")
			(teardrops
				(best_length_ratio 0.2)
				(max_length 1)
				(best_width_ratio 0.9)
				(max_width 2)
				(curved_edges yes)
				(filter_ratio 0.9)
				(enabled yes)
				(allow_two_segments yes)
				(prefer_zone_connections yes)
			)
		)
		(pad "2" smd roundrect
			(at 0.48 0 180)
			(size 0.59 0.64)
			(layers "B.Cu" "B.Mask" "B.Paste")
			(roundrect_rratio 0.25)
			(net 97 "/OCuLink/PCIe_{x4}.TX2-")
			(pintype "passive")
			(teardrops
				(best_length_ratio 0.2)
				(max_length 1)
				(best_width_ratio 0.9)
				(max_width 2)
				(curved_edges yes)
				(filter_ratio 0.9)
				(enabled yes)
				(allow_two_segments yes)
				(prefer_zone_connections yes)
			)
		)
	)
	(footprint "antmicro-footprints:R_0402_1005Metric"
		(layer "B.Cu")
		(at 144.25 137.06 180)
		(descr "Resistor SMD 0402")
		(tags "resistor SMD 0402")
		(property "Reference" "R262"
			(at -1.3 1.5 0)
			(layer "B.SilkS")
			(effects
				(font
					(size 0.7 0.7)
					(thickness 0.15)
				)
				(justify left bottom mirror)
			)
		)
		(property "Value" "R_10k_0402"
			(at -1.011843 -1.772047 0)
			(layer "B.Fab")
			(effects
				(font
					(size 0.7 0.7)
					(thickness 0.15)
				)
				(justify left bottom mirror)
			)
		)
		(property "Datasheet" "https://www.bourns.com/docs/product-datasheets/cr.pdf"
			(at 0 0 180)
			(layer "F.Fab")
			(hide yes)
			(effects
				(font
					(size 1.27 1.27)
					(thickness 0.15)
				)
			)
		)
		(property "Author" "Antmicro"
			(at 288.5 274.12 0)
			(layer "B.Fab")
			(hide yes)
			(effects
				(font
					(size 1 1)
					(thickness 0.15)
				)
				(justify mirror)
			)
		)
		(property "License" "Apache-2.0"
			(at 288.5 274.12 0)
			(layer "B.Fab")
			(hide yes)
			(effects
				(font
					(size 1 1)
					(thickness 0.15)
				)
				(justify mirror)
			)
		)
		(property "MPN" "CR0402-FX-1002GLF"
			(at 288.5 274.12 0)
			(layer "B.Fab")
			(hide yes)
			(effects
				(font
					(size 1 1)
					(thickness 0.15)
				)
				(justify mirror)
			)
		)
		(property "Manufacturer" "Bourns"
			(at 288.5 274.12 0)
			(layer "B.Fab")
			(hide yes)
			(effects
				(font
					(size 1 1)
					(thickness 0.15)
				)
				(justify mirror)
			)
		)
		(property "Public" "False"
			(at 288.5 274.12 0)
			(layer "B.Fab")
			(hide yes)
			(effects
				(font
					(size 1 1)
					(thickness 0.15)
				)
				(justify mirror)
			)
		)
		(property "Tolerance" "1%"
			(at 288.5 274.12 0)
			(layer "B.Fab")
			(hide yes)
			(effects
				(font
					(size 1 1)
					(thickness 0.15)
				)
				(justify mirror)
			)
		)
		(property "Val" "10k"
			(at 288.5 274.12 0)
			(layer "B.Fab")
			(hide yes)
			(effects
				(font
					(size 1 1)
					(thickness 0.15)
				)
				(justify mirror)
			)
		)
		(sheetname "KR to SFI #1")
		(sheetfile "kr_sfi.kicad_sch")
		(attr smd dnp)
		(fp_rect
			(start -0.925 0.47)
			(end 0.925 -0.47)
			(stroke
				(width 0.05)
				(type default)
			)
			(fill no)
			(layer "B.CrtYd")
		)
		(fp_rect
			(start -0.5 0.25)
			(end 0.5 -0.25)
			(stroke
				(width 0.15)
				(type solid)
			)
			(fill no)
			(layer "B.Fab")
		)
		(pad "1" smd roundrect
			(at -0.48 0 180)
			(size 0.59 0.64)
			(layers "B.Cu" "B.Mask" "B.Paste")
			(roundrect_rratio 0.25)
			(net 656 "Net-(U43C-PRTAD1)")
			(pintype "passive")
			(teardrops
				(best_length_ratio 0.2)
				(max_length 1)
				(best_width_ratio 0.9)
				(max_width 2)
				(curved_edges yes)
				(filter_ratio 0.9)
				(enabled yes)
				(allow_two_segments yes)
				(prefer_zone_connections yes)
			)
		)
		(pad "2" smd roundrect
			(at 0.48 0 180)
			(size 0.59 0.64)
			(layers "B.Cu" "B.Mask" "B.Paste")
			(roundrect_rratio 0.25)
			(net 78 "+1V8")
			(pintype "passive")
			(teardrops
				(best_length_ratio 0.2)
				(max_length 1)
				(best_width_ratio 0.9)
				(max_width 2)
				(curved_edges yes)
				(filter_ratio 0.9)
				(enabled yes)
				(allow_two_segments yes)
				(prefer_zone_connections yes)
			)
		)
	)
	(footprint "antmicro-footprints:TP_SMD_0.75mm"
		(layer "B.Cu")
		(at 123.4 144.66 180)
		(property "Reference" "TP52"
			(at -3.15 -0.4 0)
			(layer "B.SilkS")
			(effects
				(font
					(size 0.7 0.7)
					(thickness 0.15)
				)
				(justify left bottom mirror)
			)
		)
		(property "Value" "TP_0.75mm_SMD"
			(at 0 -1.2 0)
			(layer "B.Fab")
			(effects
				(font
					(size 0.7 0.7)
					(thickness 0.15)
				)
				(justify left bottom mirror)
			)
		)
		(property "Author" "Antmicro"
			(at 246.8 289.32 0)
			(layer "B.Fab")
			(hide yes)
			(effects
				(font
					(size 1 1)
					(thickness 0.15)
				)
				(justify mirror)
			)
		)
		(property "License" "Apache-2.0"
			(at 246.8 289.32 0)
			(layer "B.Fab")
			(hide yes)
			(effects
				(font
					(size 1 1)
					(thickness 0.15)
				)
				(justify mirror)
			)
		)
		(property "MPN" ""
			(at 246.8 289.32 0)
			(layer "B.Fab")
			(hide yes)
			(effects
				(font
					(size 1 1)
					(thickness 0.15)
				)
				(justify mirror)
			)
		)
		(property "Manufacturer" ""
			(at 246.8 289.32 0)
			(layer "B.Fab")
			(hide yes)
			(effects
				(font
					(size 1 1)
					(thickness 0.15)
				)
				(justify mirror)
			)
		)
		(property "Public" "False"
			(at 246.8 289.32 0)
			(layer "B.Fab")
			(hide yes)
			(effects
				(font
					(size 1 1)
					(thickness 0.15)
				)
				(justify mirror)
			)
		)
		(sheetname "PCIe redriver")
		(sheetfile "pcie_redriver.kicad_sch")
		(attr exclude_from_pos_files exclude_from_bom)
		(fp_circle
			(center 0 0)
			(end 0.475 0)
			(stroke
				(width 0.05)
				(type default)
			)
			(fill no)
			(layer "B.CrtYd")
		)
		(pad "1" smd circle
			(at 0 0 180)
			(size 0.75 0.75)
			(layers "B.Cu" "B.Mask")
			(net 715 "Net-(U39-~{I2C_{RESET}})")
			(pinfunction "1")
			(pintype "passive")
			(teardrops
				(best_length_ratio 0.4)
				(max_length 1)
				(best_width_ratio 0.9)
				(max_width 2)
				(curved_edges yes)
				(filter_ratio 0.9)
				(enabled yes)
				(allow_two_segments yes)
				(prefer_zone_connections yes)
			)
		)
	)
)
